# S9S_MB_2U (Grand Teton) — schematic netlist excerpt (pin names and nets, part order shuffled) for the footprints in the layout excerpt that follows; sources: Cadence DE-HDL packaged netlist, KiCad conversion of 03242023_DA0F0TMBIJ0_F0T_Motherboard_J_brd_V01_OCP.brd

PC298_P0_2  Q_CAP  1UF 16V 10% X6S  pkg C0402  page 267 : A = SW_P12V_PVCCIN_CPU0_FLT ; B = GND

PU181  RS53318LR  IC  pkg QFN21_4X3  page 258
  BST  = SW_P5V_AUX_BST
  AGND  = GND
  CS  = P5V_AUX_CS
  MODE  = P5V_AUX_MODE
  REF  = P5V_AUX_REF
  RTN  = GND
  FB  = P5V_AUX_FB
  EN  = PWRGD_P3V3_AUX
  PGOOD  = PWRGD_P5V_AUX_R
  VIN1  = SW_P5V_AUX_FLT
  PGND  = GND
  VCC  = P5V_AUX_VCC
  SW  = SW_P5V_AUX_SW
  VIN2  = SW_P5V_AUX_FLT

(kicad_pcb
	(version 20260206)
	(generator "pcbnew")
	(generator_version "10.0")
	(general
		(thickness 1.6)
		(legacy_teardrops no)
	)
	(paper "A4")
	(title_block
		(title "03242023_DA0F0TMBIJ0_F0T_Motherboard_J_brd_V01_OCP.brd")
		(comment 1 "Grand Teton / footprints 1718-1719 of 6105")
	)
	(layers
		(0 "F.Cu" signal "TOP")
		(4 "In1.Cu" signal "GND")
		(6 "In2.Cu" signal "IN1")
		(8 "In3.Cu" signal "GND1")
		(10 "In4.Cu" signal "IN2")
		(12 "In5.Cu" signal "GND2")
		(14 "In6.Cu" signal "IN3")
		(16 "In7.Cu" signal "GND3")
		(18 "In8.Cu" signal "VCC")
		(20 "In9.Cu" signal "VCC1")
		(22 "In10.Cu" signal "GND4")
		(24 "In11.Cu" signal "IN4")
		(26 "In12.Cu" signal "GND5")
		(28 "In13.Cu" signal "IN5")
		(30 "In14.Cu" signal "GND6")
		(32 "In15.Cu" signal "IN6")
		(34 "In16.Cu" signal "GND7")
		(2 "B.Cu" signal "BOTTOM")
		(9 "F.Adhes" user "F.Adhesive")
		(11 "B.Adhes" user "B.Adhesive")
		(13 "F.Paste" user "Package Geometry/Pastemask Top")
		(15 "B.Paste" user "Package Geometry/Pastemask Bottom")
		(5 "F.SilkS" user "Ref Des/Silkscreen Top")
		(7 "B.SilkS" user "Ref Des/Silkscreen Bottom")
		(1 "F.Mask" user "Board Geometry/Soldermask Top")
		(3 "B.Mask" user "Board Geometry/Soldermask Bottom")
		(17 "Dwgs.User" user "User.Drawings")
		(19 "Cmts.User" user "User.Comments")
		(21 "Eco1.User" user "User.Eco1")
		(23 "Eco2.User" user "User.Eco2")
		(25 "Edge.Cuts" user "Board Geometry/Outline")
		(27 "Margin" user)
		(31 "F.CrtYd" user "Package Geometry/Place Bound Top")
		(29 "B.CrtYd" user "Package Geometry/Place Bound Bottom")
		(35 "F.Fab" user "Ref Des/Assembly Top")
		(33 "B.Fab" user "Ref Des/Assembly Bottom")
	)
	(footprint ""
		(layer "F.Cu")
		(at 457.8477 -385.08432 90)
		(property "Reference" "PU181"
			(at 4.0894 -2.363216 0)
			(unlocked yes)
			(layer "F.SilkS")
			(effects
				(font
					(size 0.7874 0.5842)
					(thickness 0.1524)
				)
				(justify left)
			)
		)
		(property "Value" ""
			(at 0 0 90)
			(layer "F.Fab")
			(effects
				(font
					(size 1.27 1.27)
				)
			)
		)
		(duplicate_pad_numbers_are_jumpers no)
		(fp_line
			(start 1.549908 -2.050034)
			(end 0.5842 -2.050034)
			(stroke
				(width 0.1524)
				(type default)
			)
			(layer "F.SilkS")
		)
		(fp_line
			(start -0.5842 -2.050034)
			(end -1.549908 -2.050034)
			(stroke
				(width 0.1524)
				(type default)
			)
			(layer "F.SilkS")
		)
		(fp_line
			(start -1.549908 -2.050034)
			(end -1.549908 -1.9812)
			(stroke
				(width 0.1524)
				(type default)
			)
			(layer "F.SilkS")
		)
		(fp_line
			(start 1.549908 -1.9812)
			(end 1.549908 -2.050034)
			(stroke
				(width 0.1524)
				(type default)
			)
			(layer "F.SilkS")
		)
		(fp_line
			(start -1.549908 1.9812)
			(end -1.549908 2.050034)
			(stroke
				(width 0.1524)
				(type default)
			)
			(layer "F.SilkS")
		)
		(fp_line
			(start 1.549908 2.050034)
			(end 1.549908 1.9304)
			(stroke
				(width 0.1524)
				(type default)
			)
			(layer "F.SilkS")
		)
		(fp_line
			(start 0 2.050034)
			(end 1.549908 2.050034)
			(stroke
				(width 0.1524)
				(type default)
			)
			(layer "F.SilkS")
		)
		(fp_line
			(start -1.549908 2.050034)
			(end -0.5842 2.050034)
			(stroke
				(width 0.1524)
				(type default)
			)
			(layer "F.SilkS")
		)
		(fp_poly
			(pts
				(xy -2.9464 -2.208022) (xy -2.9464 -1.192022) (xy -1.9304 -1.700022)
			)
			(stroke
				(width 0)
				(type default)
			)
			(fill yes)
			(layer "F.SilkS")
		)
		(fp_line
			(start 1.549908 -2.050034)
			(end -1.549908 -2.050034)
			(stroke
				(width 0.1)
				(type default)
			)
			(layer "F.Fab")
		)
		(fp_line
			(start -1.549908 -2.050034)
			(end -1.549908 2.050034)
			(stroke
				(width 0.1)
				(type default)
			)
			(layer "F.Fab")
		)
		(fp_line
			(start 1.549908 2.050034)
			(end 1.549908 -2.050034)
			(stroke
				(width 0.1)
				(type default)
			)
			(layer "F.Fab")
		)
		(fp_line
			(start -1.549908 2.050034)
			(end 1.549908 2.050034)
			(stroke
				(width 0.1)
				(type default)
			)
			(layer "F.Fab")
		)
		(fp_poly
			(pts
				(xy -2.9464 -2.208022) (xy -2.9464 -1.192022) (xy -1.9304 -1.700022)
			)
			(stroke
				(width 0)
				(type default)
			)
			(fill yes)
			(layer "F.Fab")
		)
		(pad "1" smd circle
			(at -1.35001 -1.700022 90)
			(size 0 0)
			(layers "F.Cu" "F.Mask" "F.Paste")
			(net "SW_P5V_AUX_BST")
		)
		(pad "2" smd rect
			(at -1.400048 -1.199896 180)
			(size 0.1778 0.8128)
			(layers "F.Cu" "F.Mask" "F.Paste")
			(net "GND")
		)
		(pad "3" smd rect
			(at -1.400048 -0.8001 180)
			(size 0.1778 0.8128)
			(layers "F.Cu" "F.Mask" "F.Paste")
			(net "P5V_AUX_CS")
		)
		(pad "4" smd rect
			(at -1.400048 -0.40005 180)
			(size 0.1778 0.8128)
			(layers "F.Cu" "F.Mask" "F.Paste")
			(net "P5V_AUX_MODE")
		)
		(pad "5" smd rect
			(at -1.400048 0 180)
			(size 0.1778 0.8128)
			(layers "F.Cu" "F.Mask" "F.Paste")
			(net "P5V_AUX_REF")
		)
		(pad "6" smd rect
			(at -1.400048 0.40005 180)
			(size 0.1778 0.8128)
			(layers "F.Cu" "F.Mask" "F.Paste")
			(net "GND")
		)
		(pad "7" smd rect
			(at -1.400048 0.8001 180)
			(size 0.1778 0.8128)
			(layers "F.Cu" "F.Mask" "F.Paste")
			(net "P5V_AUX_FB")
		)
		(pad "8" smd rect
			(at -1.400048 1.199896 180)
			(size 0.1778 0.8128)
			(layers "F.Cu" "F.Mask" "F.Paste")
			(net "PWRGD_P3V3_AUX")
		)
		(pad "9" smd rect
			(at -1.400048 1.700022 180)
			(size 0.3048 0.8128)
			(layers "F.Cu" "F.Mask" "F.Paste")
			(net "PWRGD_P5V_AUX_R")
		)
		(pad "10" smd rect
			(at -0.299974 1.299972 90)
			(size 0.3048 2.0066)
			(layers "F.Cu" "F.Mask" "F.Paste")
			(net "SW_P5V_AUX_FLT")
		)
		(pad "11_18" smd circle
			(at 1.175004 0.275082 90)
			(size 0 0)
			(layers "F.Cu" "F.Mask" "F.Paste")
			(net "GND")
		)
		(pad "19" smd rect
			(at 1.400048 -1.700022)
			(size 0.3048 0.8128)
			(layers "F.Cu" "F.Mask" "F.Paste")
			(net "P5V_AUX_VCC")
		)
		(pad "20" smd rect
			(at 0.299974 -1.299972 90)
			(size 0.3048 2.0066)
			(layers "F.Cu" "F.Mask" "F.Paste")
			(net "SW_P5V_AUX_SW")
		)
		(pad "21" smd rect
			(at -0.299974 -1.299972 90)
			(size 0.3048 2.0066)
			(layers "F.Cu" "F.Mask" "F.Paste")
			(net "SW_P5V_AUX_FLT")
		)
	)
	(footprint ""
		(layer "F.Cu")
		(at 356.667308 -333.804514 -90)
		(property "Reference" "PC298_P0_2"
			(at 0 0 270)
			(layer "F.SilkS")
			(hide yes)
			(effects
				(font
					(size 1.27 1.27)
				)
			)
		)
		(property "Value" ""
			(at 0 0 270)
			(layer "F.Fab")
			(effects
				(font
					(size 1.27 1.27)
				)
			)
		)
		(duplicate_pad_numbers_are_jumpers no)
		(fp_line
			(start -0.7874 0.4064)
			(end -0.7874 -0.4064)
			(stroke
				(width 0.1524)
				(type default)
			)
			(layer "F.SilkS")
		)
		(fp_line
			(start 0.7874 0.4064)
			(end -0.7874 0.4064)
			(stroke
				(width 0.1524)
				(type default)
			)
			(layer "F.SilkS")
		)
		(fp_line
			(start -0.7874 -0.4064)
			(end 0.7874 -0.4064)
			(stroke
				(width 0.1524)
				(type default)
			)
			(layer "F.SilkS")
		)
		(fp_line
			(start 0.7874 -0.4064)
			(end 0.7874 0.4064)
			(stroke
				(width 0.1524)
				(type default)
			)
			(layer "F.SilkS")
		)
		(fp_line
			(start -0.67945 0.3048)
			(end -0.67945 -0.305054)
			(stroke
				(width 0.1)
				(type default)
			)
			(layer "F.Fab")
		)
		(fp_line
			(start -0.12065 0.3048)
			(end -0.67945 0.3048)
			(stroke
				(width 0.1)
				(type default)
			)
			(layer "F.Fab")
		)
		(fp_line
			(start 0.120396 0.3048)
			(end 0.120396 0.2794)
			(stroke
				(width 0.1)
				(type default)
			)
			(layer "F.Fab")
		)
		(fp_line
			(start 0.67945 0.3048)
			(end 0.120396 0.3048)
			(stroke
				(width 0.1)
				(type default)
			)
			(layer "F.Fab")
		)
		(fp_line
			(start -0.12065 0.2794)
			(end -0.12065 0.3048)
			(stroke
				(width 0.1)
				(type default)
			)
			(layer "F.Fab")
		)
		(fp_line
			(start 0.120396 0.2794)
			(end -0.12065 0.2794)
			(stroke
				(width 0.1)
				(type default)
			)
			(layer "F.Fab")
		)
		(fp_line
			(start -0.12065 -0.2794)
			(end 0.12065 -0.2794)
			(stroke
				(width 0.1)
				(type default)
			)
			(layer "F.Fab")
		)
		(fp_line
			(start 0.12065 -0.2794)
			(end 0.12065 -0.3048)
			(stroke
				(width 0.1)
				(type default)
			)
			(layer "F.Fab")
		)
		(fp_line
			(start 0.12065 -0.3048)
			(end 0.67945 -0.3048)
			(stroke
				(width 0.1)
				(type default)
			)
			(layer "F.Fab")
		)
		(fp_line
			(start 0.67945 -0.3048)
			(end 0.67945 0.3048)
			(stroke
				(width 0.1)
				(type default)
			)
			(layer "F.Fab")
		)
		(fp_line
			(start -0.67945 -0.305054)
			(end -0.12065 -0.305054)
			(stroke
				(width 0.1)
				(type default)
			)
			(layer "F.Fab")
		)
		(fp_line
			(start -0.12065 -0.305054)
			(end -0.12065 -0.2794)
			(stroke
				(width 0.1)
				(type default)
			)
			(layer "F.Fab")
		)
		(pad "1" smd circle
			(at -0.40005 0 270)
			(size 0 0)
			(layers "F.Cu" "F.Mask" "F.Paste")
			(net "SW_P12V_PVCCIN_CPU0_FLT")
		)
		(pad "2" smd circle
			(at 0.40005 0 270)
			(size 0 0)
			(layers "F.Cu" "F.Mask" "F.Paste")
			(net "GND")
		)
	)
)
